(kicad_pcb
	(version 20260206)
	(generator "pcbnew")
	(generator_version "10.0")
	(general
		(thickness 1.6)
		(legacy_teardrops no)
	)
	(paper "A4")
	(title_block
		(title "Bryce Canyon_R.DPB_16317-1_OCP.brd")
		(comment 1 "Bryce Canyon / footprints 1874-1880 of 2099")
	)
	(layers
		(0 "F.Cu" signal "TOP")
		(4 "In1.Cu" signal "L2GND")
		(6 "In2.Cu" signal "L3")
		(8 "In3.Cu" signal "L4VCC")
		(10 "In4.Cu" signal "L5VCC")
		(12 "In5.Cu" signal "L6")
		(14 "In6.Cu" signal "L7GND")
		(2 "B.Cu" signal "BOTTOM")
		(9 "F.Adhes" user "F.Adhesive")
		(11 "B.Adhes" user "B.Adhesive")
		(13 "F.Paste" user "Package Geometry/Pastemask Top")
		(15 "B.Paste" user "Package Geometry/Pastemask Bottom")
		(5 "F.SilkS" user "Ref Des/Silkscreen Top")
		(7 "B.SilkS" user "Ref Des/Silkscreen Bottom")
		(1 "F.Mask" user "Board Geometry/Soldermask Top")
		(3 "B.Mask" user "Board Geometry/Soldermask Bottom")
		(17 "Dwgs.User" user "User.Drawings")
		(19 "Cmts.User" user "User.Comments")
		(21 "Eco1.User" user "User.Eco1")
		(23 "Eco2.User" user "User.Eco2")
		(25 "Edge.Cuts" user "Board Geometry/Outline")
		(27 "Margin" user)
		(31 "F.CrtYd" user "Package Geometry/Place Bound Top")
		(29 "B.CrtYd" user "Package Geometry/Place Bound Bottom")
		(35 "F.Fab" user "Ref Des/Assembly Top")
		(33 "B.Fab" user "Ref Des/Assembly Bottom")
	)
	(footprint ""
		(layer "F.Cu")
		(at 179.7812 -130.8608 180)
		(property "Reference" "R471"
			(at 0 0 180)
			(layer "F.SilkS")
			(hide yes)
			(effects
				(font
					(size 1.27 1.27)
				)
			)
		)
		(property "Value" "0R2J-2-GP"
			(at 0.064008 -3.993896 180)
			(unlocked yes)
			(layer "F.Fab")
			(hide yes)
			(effects
				(font
					(size 1.016 1.016)
					(thickness 0.1524)
				)
			)
		)
		(property "Device Type" "R402H16"
			(at 0.064008 -5.517896 180)
			(unlocked yes)
			(layer "F.Fab")
			(hide yes)
			(effects
				(font
					(size 1.016 1.016)
					(thickness 0.1524)
				)
			)
		)
		(duplicate_pad_numbers_are_jumpers no)
		(fp_line
			(start 0.508 -0.9398)
			(end -0.508 -0.9398)
			(stroke
				(width 0.1524)
				(type default)
			)
			(layer "F.SilkS")
		)
		(fp_line
			(start -0.508 -0.9398)
			(end -0.508 0.9398)
			(stroke
				(width 0.1524)
				(type default)
			)
			(layer "F.SilkS")
		)
		(fp_rect
			(start -0.508 0.9398)
			(end 0.508 -0.9398)
			(stroke
				(width 0)
				(type default)
			)
			(fill no)
			(layer "F.CrtYd")
		)
		(fp_rect
			(start -0.508 0.9398)
			(end 0.508 -0.9398)
			(stroke
				(width 0)
				(type default)
			)
			(fill no)
			(layer "F.Fab")
		)
		(pad "1" smd custom
			(at 0 -0.4445 180)
			(size 0.1397 0.1397)
			(layers "F.Cu" "F.Mask" "F.Paste")
			(net "DRIVE_B_17_PWR")
			(options
				(clearance outline)
				(anchor circle)
			)
			(primitives
				(gr_poly
					(pts
						(arc
							(start -0.1778 -0.2794)
							(mid -0.249642 -0.249642)
							(end -0.2794 -0.1778)
						)
						(arc
							(start -0.2794 0.1778)
							(mid -0.249642 0.249642)
							(end -0.1778 0.2794)
						)
						(arc
							(start 0.1778 0.2794)
							(mid 0.249642 0.249642)
							(end 0.2794 0.1778)
						)
						(arc
							(start 0.2794 -0.1778)
							(mid 0.249642 -0.249642)
							(end 0.1778 -0.2794)
						)
					)
					(width 0)
					(fill yes)
				)
			)
		)
		(pad "2" smd custom
			(at 0 0.4445 180)
			(size 0.1397 0.1397)
			(layers "F.Cu" "F.Mask" "F.Paste")
			(net "SW_PWR_R_HDD17")
			(options
				(clearance outline)
				(anchor circle)
			)
			(primitives
				(gr_poly
					(pts
						(arc
							(start -0.1778 -0.2794)
							(mid -0.249642 -0.249642)
							(end -0.2794 -0.1778)
						)
						(arc
							(start -0.2794 0.1778)
							(mid -0.249642 0.249642)
							(end -0.1778 0.2794)
						)
						(arc
							(start 0.1778 0.2794)
							(mid 0.249642 0.249642)
							(end 0.2794 0.1778)
						)
						(arc
							(start 0.2794 -0.1778)
							(mid 0.249642 -0.249642)
							(end 0.1778 -0.2794)
						)
					)
					(width 0)
					(fill yes)
				)
			)
		)
	)
	(footprint ""
		(layer "F.Cu")
		(at 471.805 -139.065 -90)
		(property "Reference" "C337"
			(at 0 0 270)
			(layer "F.SilkS")
			(hide yes)
			(effects
				(font
					(size 1.27 1.27)
				)
			)
		)
		(property "Value" "SCD033U25V2KX-GP"
			(at 1.1811 -2.7051 270)
			(unlocked yes)
			(layer "F.Fab")
			(hide yes)
			(effects
				(font
					(size 1.016 1.016)
					(thickness 0.1524)
				)
			)
		)
		(property "Device Type" "C402H22"
			(at 1.1811 -4.2291 270)
			(unlocked yes)
			(layer "F.Fab")
			(hide yes)
			(effects
				(font
					(size 1.016 1.016)
					(thickness 0.1524)
				)
			)
		)
		(duplicate_pad_numbers_are_jumpers no)
		(fp_rect
			(start -0.4318 0.9525)
			(end 0.4318 -0.9525)
			(stroke
				(width 0)
				(type default)
			)
			(fill no)
			(layer "F.CrtYd")
		)
		(fp_rect
			(start -0.4318 0.9525)
			(end 0.4318 -0.9525)
			(stroke
				(width 0)
				(type default)
			)
			(fill no)
			(layer "F.Fab")
		)
		(pad "1" smd custom
			(at 0 -0.4445 270)
			(size 0.1524 0.1524)
			(layers "F.Cu" "F.Mask" "F.Paste")
			(net "SW_HDD_P23")
			(options
				(clearance outline)
				(anchor circle)
			)
			(primitives
				(gr_poly
					(pts
						(arc
							(start 0.3048 -0.2032)
							(mid 0.275042 -0.275042)
							(end 0.2032 -0.3048)
						)
						(arc
							(start -0.2032 -0.3048)
							(mid -0.275042 -0.275042)
							(end -0.3048 -0.2032)
						)
						(arc
							(start -0.3048 0.2032)
							(mid -0.275042 0.275042)
							(end -0.2032 0.3048)
						)
						(arc
							(start 0.2032 0.3048)
							(mid 0.275042 0.275042)
							(end 0.3048 0.2032)
						)
					)
					(width 0)
					(fill yes)
				)
			)
		)
		(pad "2" smd custom
			(at 0 0.4445 270)
			(size 0.1524 0.1524)
			(layers "F.Cu" "F.Mask" "F.Paste")
			(net "GND")
			(options
				(clearance outline)
				(anchor circle)
			)
			(primitives
				(gr_poly
					(pts
						(arc
							(start 0.3048 -0.2032)
							(mid 0.275042 -0.275042)
							(end 0.2032 -0.3048)
						)
						(arc
							(start -0.2032 -0.3048)
							(mid -0.275042 -0.275042)
							(end -0.3048 -0.2032)
						)
						(arc
							(start -0.3048 0.2032)
							(mid -0.275042 0.275042)
							(end -0.2032 0.3048)
						)
						(arc
							(start 0.2032 0.3048)
							(mid 0.275042 0.275042)
							(end 0.3048 0.2032)
						)
					)
					(width 0)
					(fill yes)
				)
			)
		)
	)
	(footprint ""
		(layer "F.Cu")
		(at 27.437588 -229.5017 -90)
		(property "Reference" "R1102"
			(at 0 0 270)
			(layer "F.SilkS")
			(hide yes)
			(effects
				(font
					(size 1.27 1.27)
				)
			)
		)
		(property "Value" "10KR2F-2-GP"
			(at 0.064008 -3.993896 270)
			(unlocked yes)
			(layer "F.Fab")
			(hide yes)
			(effects
				(font
					(size 1.016 1.016)
					(thickness 0.1524)
				)
			)
		)
		(property "Device Type" "R402H16"
			(at 0.064008 -5.517896 270)
			(unlocked yes)
			(layer "F.Fab")
			(hide yes)
			(effects
				(font
					(size 1.016 1.016)
					(thickness 0.1524)
				)
			)
		)
		(duplicate_pad_numbers_are_jumpers no)
		(fp_line
			(start -0.508 -0.9398)
			(end -0.508 0.9398)
			(stroke
				(width 0.1524)
				(type default)
			)
			(layer "F.SilkS")
		)
		(fp_line
			(start 0.508 -0.9398)
			(end -0.508 -0.9398)
			(stroke
				(width 0.1524)
				(type default)
			)
			(layer "F.SilkS")
		)
		(fp_rect
			(start -0.508 0.9398)
			(end 0.508 -0.9398)
			(stroke
				(width 0)
				(type default)
			)
			(fill no)
			(layer "F.CrtYd")
		)
		(fp_rect
			(start -0.508 0.9398)
			(end 0.508 -0.9398)
			(stroke
				(width 0)
				(type default)
			)
			(fill no)
			(layer "F.Fab")
		)
		(pad "1" smd custom
			(at 0 -0.4445 270)
			(size 0.1397 0.1397)
			(layers "F.Cu" "F.Mask" "F.Paste")
			(net "P5V_B_1")
			(options
				(clearance outline)
				(anchor circle)
			)
			(primitives
				(gr_poly
					(pts
						(arc
							(start -0.1778 -0.2794)
							(mid -0.249642 -0.249642)
							(end -0.2794 -0.1778)
						)
						(arc
							(start -0.2794 0.1778)
							(mid -0.249642 0.249642)
							(end -0.1778 0.2794)
						)
						(arc
							(start 0.1778 0.2794)
							(mid 0.249642 0.249642)
							(end 0.2794 0.1778)
						)
						(arc
							(start 0.2794 -0.1778)
							(mid 0.249642 -0.249642)
							(end 0.1778 -0.2794)
						)
					)
					(width 0)
					(fill yes)
				)
			)
		)
		(pad "2" smd custom
			(at 0 0.4445 270)
			(size 0.1397 0.1397)
			(layers "F.Cu" "F.Mask" "F.Paste")
			(net "P5V_B_1_PGOOD")
			(options
				(clearance outline)
				(anchor circle)
			)
			(primitives
				(gr_poly
					(pts
						(arc
							(start -0.1778 -0.2794)
							(mid -0.249642 -0.249642)
							(end -0.2794 -0.1778)
						)
						(arc
							(start -0.2794 0.1778)
							(mid -0.249642 0.249642)
							(end -0.1778 0.2794)
						)
						(arc
							(start 0.1778 0.2794)
							(mid 0.249642 0.249642)
							(end 0.2794 0.1778)
						)
						(arc
							(start 0.2794 -0.1778)
							(mid 0.249642 -0.249642)
							(end 0.1778 -0.2794)
						)
					)
					(width 0)
					(fill yes)
				)
			)
		)
	)
	(footprint ""
		(layer "F.Cu")
		(at 273.5834 -328.28484 90)
		(property "Reference" "R92"
			(at 0 0 90)
			(layer "F.SilkS")
			(hide yes)
			(effects
				(font
					(size 1.27 1.27)
				)
			)
		)
		(property "Value" "4K7R2F-GP"
			(at 0.064008 -3.993896 90)
			(unlocked yes)
			(layer "F.Fab")
			(hide yes)
			(effects
				(font
					(size 1.016 1.016)
					(thickness 0.1524)
				)
			)
		)
		(property "Device Type" "R402H16"
			(at 0.064008 -5.517896 90)
			(unlocked yes)
			(layer "F.Fab")
			(hide yes)
			(effects
				(font
					(size 1.016 1.016)
					(thickness 0.1524)
				)
			)
		)
		(duplicate_pad_numbers_are_jumpers no)
		(fp_line
			(start 0.508 -0.9398)
			(end -0.508 -0.9398)
			(stroke
				(width 0.1524)
				(type default)
			)
			(layer "F.SilkS")
		)
		(fp_line
			(start -0.508 -0.9398)
			(end -0.508 0.9398)
			(stroke
				(width 0.1524)
				(type default)
			)
			(layer "F.SilkS")
		)
		(fp_rect
			(start -0.508 0.9398)
			(end 0.508 -0.9398)
			(stroke
				(width 0)
				(type default)
			)
			(fill no)
			(layer "F.CrtYd")
		)
		(fp_rect
			(start -0.508 0.9398)
			(end 0.508 -0.9398)
			(stroke
				(width 0)
				(type default)
			)
			(fill no)
			(layer "F.Fab")
		)
		(pad "1" smd custom
			(at 0 -0.4445 90)
			(size 0.1397 0.1397)
			(layers "F.Cu" "F.Mask" "F.Paste")
			(net "P3V3_IN")
			(options
				(clearance outline)
				(anchor circle)
			)
			(primitives
				(gr_poly
					(pts
						(arc
							(start -0.1778 -0.2794)
							(mid -0.249642 -0.249642)
							(end -0.2794 -0.1778)
						)
						(arc
							(start -0.2794 0.1778)
							(mid -0.249642 0.249642)
							(end -0.1778 0.2794)
						)
						(arc
							(start 0.1778 0.2794)
							(mid 0.249642 0.249642)
							(end 0.2794 0.1778)
						)
						(arc
							(start 0.2794 -0.1778)
							(mid 0.249642 -0.249642)
							(end 0.1778 -0.2794)
						)
					)
					(width 0)
					(fill yes)
				)
			)
		)
		(pad "2" smd custom
			(at 0 0.4445 90)
			(size 0.1397 0.1397)
			(layers "F.Cu" "F.Mask" "F.Paste")
			(net "PWM_OUT_FAN0")
			(options
				(clearance outline)
				(anchor circle)
			)
			(primitives
				(gr_poly
					(pts
						(arc
							(start -0.1778 -0.2794)
							(mid -0.249642 -0.249642)
							(end -0.2794 -0.1778)
						)
						(arc
							(start -0.2794 0.1778)
							(mid -0.249642 0.249642)
							(end -0.1778 0.2794)
						)
						(arc
							(start 0.1778 0.2794)
							(mid 0.249642 0.249642)
							(end 0.2794 0.1778)
						)
						(arc
							(start 0.2794 -0.1778)
							(mid 0.249642 -0.249642)
							(end 0.1778 -0.2794)
						)
					)
					(width 0)
					(fill yes)
				)
			)
		)
	)
	(footprint ""
		(layer "F.Cu")
		(at 184.277 -369.189 90)
		(property "Reference" "R994"
			(at 0 0 90)
			(layer "F.SilkS")
			(hide yes)
			(effects
				(font
					(size 1.27 1.27)
				)
			)
		)
		(property "Value" "1K4R2F-1-GP"
			(at 0.064008 -3.993896 90)
			(unlocked yes)
			(layer "F.Fab")
			(hide yes)
			(effects
				(font
					(size 1.016 1.016)
					(thickness 0.1524)
				)
			)
		)
		(property "Device Type" "R402H16"
			(at 0.064008 -5.517896 90)
			(unlocked yes)
			(layer "F.Fab")
			(hide yes)
			(effects
				(font
					(size 1.016 1.016)
					(thickness 0.1524)
				)
			)
		)
		(duplicate_pad_numbers_are_jumpers no)
		(fp_line
			(start 0.508 -0.9398)
			(end -0.508 -0.9398)
			(stroke
				(width 0.1524)
				(type default)
			)
			(layer "F.SilkS")
		)
		(fp_line
			(start -0.508 -0.9398)
			(end -0.508 0.9398)
			(stroke
				(width 0.1524)
				(type default)
			)
			(layer "F.SilkS")
		)
		(fp_rect
			(start -0.508 0.9398)
			(end 0.508 -0.9398)
			(stroke
				(width 0)
				(type default)
			)
			(fill no)
			(layer "F.CrtYd")
		)
		(fp_rect
			(start -0.508 0.9398)
			(end 0.508 -0.9398)
			(stroke
				(width 0)
				(type default)
			)
			(fill no)
			(layer "F.Fab")
		)
		(pad "1" smd custom
			(at 0 -0.4445 90)
			(size 0.1397 0.1397)
			(layers "F.Cu" "F.Mask" "F.Paste")
			(net "12V_HS_ENABLE")
			(options
				(clearance outline)
				(anchor circle)
			)
			(primitives
				(gr_poly
					(pts
						(arc
							(start -0.1778 -0.2794)
							(mid -0.249642 -0.249642)
							(end -0.2794 -0.1778)
						)
						(arc
							(start -0.2794 0.1778)
							(mid -0.249642 0.249642)
							(end -0.1778 0.2794)
						)
						(arc
							(start 0.1778 0.2794)
							(mid 0.249642 0.249642)
							(end 0.2794 0.1778)
						)
						(arc
							(start 0.2794 -0.1778)
							(mid 0.249642 -0.249642)
							(end 0.1778 -0.2794)
						)
					)
					(width 0)
					(fill yes)
				)
			)
		)
		(pad "2" smd custom
			(at 0 0.4445 90)
			(size 0.1397 0.1397)
			(layers "F.Cu" "F.Mask" "F.Paste")
			(net "GND")
			(options
				(clearance outline)
				(anchor circle)
			)
			(primitives
				(gr_poly
					(pts
						(arc
							(start -0.1778 -0.2794)
							(mid -0.249642 -0.249642)
							(end -0.2794 -0.1778)
						)
						(arc
							(start -0.2794 0.1778)
							(mid -0.249642 0.249642)
							(end -0.1778 0.2794)
						)
						(arc
							(start 0.1778 0.2794)
							(mid 0.249642 0.249642)
							(end 0.2794 0.1778)
						)
						(arc
							(start 0.2794 -0.1778)
							(mid 0.249642 -0.249642)
							(end 0.1778 -0.2794)
						)
					)
					(width 0)
					(fill yes)
				)
			)
		)
	)
	(footprint ""
		(layer "F.Cu")
		(at 401.4216 -33.909 90)
		(property "Reference" "Q168"
			(at 0 0 90)
			(layer "F.SilkS")
			(hide yes)
			(effects
				(font
					(size 1.27 1.27)
				)
			)
		)
		(property "Value" "AO4407AL-GP"
			(at -3.707384 -1.5367 90)
			(unlocked yes)
			(layer "F.Fab")
			(hide yes)
			(effects
				(font
					(size 1.016 1.016)
					(thickness 0.1524)
				)
			)
		)
		(property "Device Type" "SOIC8H69"
			(at -3.707384 -3.0607 90)
			(unlocked yes)
			(layer "F.Fab")
			(hide yes)
			(effects
				(font
					(size 1.016 1.016)
					(thickness 0.1524)
				)
			)
		)
		(duplicate_pad_numbers_are_jumpers no)
		(fp_line
			(start 2.1336 -1.4224)
			(end -2.7432 -1.4224)
			(stroke
				(width 0.1524)
				(type default)
			)
			(layer "F.SilkS")
		)
		(fp_line
			(start -2.7432 -1.4224)
			(end -2.7432 1.4224)
			(stroke
				(width 0.1524)
				(type default)
			)
			(layer "F.SilkS")
		)
		(fp_line
			(start -2.7178 -0.508)
			(end -2.1844 -0.0508)
			(stroke
				(width 0.1524)
				(type default)
			)
			(layer "F.SilkS")
		)
		(fp_line
			(start -2.1844 -0.0508)
			(end -2.7178 0.508)
			(stroke
				(width 0.1524)
				(type default)
			)
			(layer "F.SilkS")
		)
		(fp_line
			(start 2.1336 1.4224)
			(end 2.1336 -1.4224)
			(stroke
				(width 0.1524)
				(type default)
			)
			(layer "F.SilkS")
		)
		(fp_line
			(start -2.7432 1.4224)
			(end 2.1336 1.4224)
			(stroke
				(width 0.1524)
				(type default)
			)
			(layer "F.SilkS")
		)
		(fp_line
			(start -2.7432 1.4224)
			(end -2.6416 1.4224)
			(stroke
				(width 0.1524)
				(type default)
			)
			(layer "F.SilkS")
		)
		(fp_line
			(start -2.6289 3.4417)
			(end -2.6289 1.4732)
			(stroke
				(width 0.381)
				(type default)
			)
			(layer "F.SilkS")
		)
		(fp_poly
			(pts
				(xy -2.2098 -1.4224) (xy -2.2098 1.4224) (xy 2.2098 1.4224) (xy 2.2098 -1.4224)
			)
			(stroke
				(width 0)
				(type default)
			)
			(fill yes)
			(layer "F.SilkS")
		)
		(fp_rect
			(start -2.450084 2.999994)
			(end 2.450084 -2.999994)
			(stroke
				(width 0)
				(type default)
			)
			(fill no)
			(layer "F.CrtYd")
		)
		(fp_poly
			(pts
				(xy -2.8194 3.6322) (xy -2.8194 -3.6322) (xy 2.8194 -3.6322) (xy 2.8194 1.18364) (xy 2.450084 1.18364)
				(xy 2.450084 -2.999994) (xy -2.450084 -2.999994) (xy -2.450084 2.999994) (xy 2.450084 2.999994)
				(xy 2.450084 1.18618) (xy 2.8194 1.18618) (xy 2.8194 3.6322)
			)
			(stroke
				(width 0)
				(type default)
			)
			(fill no)
			(layer "F.CrtYd")
		)
		(fp_rect
			(start -2.8194 3.6322)
			(end 2.8194 -3.6322)
			(stroke
				(width 0)
				(type default)
			)
			(fill no)
			(layer "F.Fab")
		)
		(pad "1" smd rect
			(at -1.905 2.54 90)
			(size 0.635 1.651)
			(layers "F.Cu" "F.Mask" "F.Paste")
			(net "P12V_B")
		)
		(pad "2" smd rect
			(at -0.635 2.54 90)
			(size 0.635 1.651)
			(layers "F.Cu" "F.Mask" "F.Paste")
			(net "P12V_B")
		)
		(pad "3" smd rect
			(at 0.635 2.54 90)
			(size 0.635 1.651)
			(layers "F.Cu" "F.Mask" "F.Paste")
			(net "P12V_B")
		)
		(pad "4" smd rect
			(at 1.905 2.54 90)
			(size 0.635 1.651)
			(layers "F.Cu" "F.Mask" "F.Paste")
			(net "SW_HDD_N32")
		)
		(pad "5" smd rect
			(at 1.905 -2.54 90)
			(size 0.635 1.651)
			(layers "F.Cu" "F.Mask" "F.Paste")
			(net "P12V_HDD32")
		)
		(pad "6" smd rect
			(at 0.635 -2.54 90)
			(size 0.635 1.651)
			(layers "F.Cu" "F.Mask" "F.Paste")
			(net "P12V_HDD32")
		)
		(pad "7" smd rect
			(at -0.635 -2.54 90)
			(size 0.635 1.651)
			(layers "F.Cu" "F.Mask" "F.Paste")
			(net "P12V_HDD32")
		)
		(pad "8" smd rect
			(at -1.905 -2.54 90)
			(size 0.635 1.651)
			(layers "F.Cu" "F.Mask" "F.Paste")
			(net "P12V_HDD32")
		)
	)
	(footprint ""
		(layer "F.Cu")
		(at 18.923 -265.684 90)
		(property "Reference" "R899"
			(at 0 0 90)
			(layer "F.SilkS")
			(hide yes)
			(effects
				(font
					(size 1.27 1.27)
				)
			)
		)
		(property "Value" "2R6F-GP"
			(at -0.0508 -4.8514 90)
			(unlocked yes)
			(layer "F.Fab")
			(hide yes)
			(effects
				(font
					(size 1.016 1.016)
					(thickness 0.1524)
				)
			)
		)
		(property "Device Type" "R1206H26"
			(at 0 -6.3754 90)
			(unlocked yes)
			(layer "F.Fab")
			(hide yes)
			(effects
				(font
					(size 1.016 1.016)
					(thickness 0.1524)
				)
			)
		)
		(duplicate_pad_numbers_are_jumpers no)
		(fp_line
			(start 1.016 -2.2352)
			(end 1.016 2.2352)
			(stroke
				(width 0.1524)
				(type default)
			)
			(layer "F.SilkS")
		)
		(fp_line
			(start -1.016 -2.2352)
			(end 1.016 -2.2352)
			(stroke
				(width 0.1524)
				(type default)
			)
			(layer "F.SilkS")
		)
		(fp_line
			(start 1.016 2.2352)
			(end -1.016 2.2352)
			(stroke
				(width 0.1524)
				(type default)
			)
			(layer "F.SilkS")
		)
		(fp_line
			(start -1.016 2.2352)
			(end -1.016 -2.2352)
			(stroke
				(width 0.1524)
				(type default)
			)
			(layer "F.SilkS")
		)
		(fp_rect
			(start -1.0922 2.3114)
			(end 1.0922 -2.3114)
			(stroke
				(width 0)
				(type default)
			)
			(fill no)
			(layer "F.CrtYd")
		)
		(fp_poly
			(pts
				(xy -1.0922 -2.3114) (xy 1.0922 -2.3114) (xy 1.0922 2.3114) (xy -1.0922 2.3114)
			)
			(stroke
				(width 0)
				(type default)
			)
			(fill no)
			(layer "F.Fab")
		)
		(pad "1" smd rect
			(at 0 -1.397 90)
			(size 1.651 1.27)
			(layers "F.Cu" "F.Mask" "F.Paste")
			(net "P12V_HDD0")
		)
		(pad "2" smd rect
			(at 0 1.397 90)
			(size 1.651 1.27)
			(layers "F.Cu" "F.Mask" "F.Paste")
			(net "12V_PRE_0")
		)
	)
)
